# S9S_MB_2U (Grand Teton) — schematic netlist excerpt (pin names and nets, part order shuffled) for the footprints in the layout excerpt that follows; sources: Cadence DE-HDL packaged netlist, KiCad conversion of 03242023_DA0F0TMBIJ0_F0T_Motherboard_J_brd_V01_OCP.brd

J30  SCONN288_ADR50017P087CC  SCONN288_ADR50017-P087CC IO  pkg DDR288S_1-1VXB  page 111
  VIN_BULK0  = P12V_S3_AUX_CPU1_NVDIMM
  RFU0  = TP_CHG_CPU1_DIMM2_FRU_0
  VIN_MGMT  = P3V3_AUX
  HSCL  = I3C_SPD_DDREFGH_CPU1_LVC1_SCL_5
  HSDA  = I3C_SPD_DDREFGH_CPU1_LVC1_SDA
  VSS0  = GND
  DQ0_A  = M_G_CPU1_SA_DQ<0>
  VSS1  = GND
  DQ1_A  = M_G_CPU1_SA_DQ<1>
  VSS2  = GND
  DQS0_A_T  = M_G_CPU1_SA_DQS_DP<0>
  DQS0_A_C  = M_G_CPU1_SA_DQS_DN<0>
  VSS3  = GND
  DQ4_A  = M_G_CPU1_SA_DQ<4>
  VSS4  = GND
  DQ5_A  = M_G_CPU1_SA_DQ<5>
  VSS5  = GND
  DQ8_A  = M_G_CPU1_SA_DQ<8>
  VSS6  = GND
  DQ9_A  = M_G_CPU1_SA_DQ<9>
  VSS7  = GND
  DQS1_A_T  = M_G_CPU1_SA_DQS_DP<1>
  DQS1_A_C  = M_G_CPU1_SA_DQS_DN<1>
  VSS8  = GND
  DQ12_A  = M_G_CPU1_SA_DQ<12>
  VSS9  = GND
  DQ13_A  = M_G_CPU1_SA_DQ<13>
  VSS10  = GND
  DQ16_A  = M_G_CPU1_SA_DQ<16>
  VSS11  = GND
  DQ17_A  = M_G_CPU1_SA_DQ<17>
  VSS12  = GND
  DQS2_A_T  = M_G_CPU1_SA_DQS_DP<2>
  DQS2_A_C  = M_G_CPU1_SA_DQS_DN<2>
  VSS13  = GND
  DQ20_A  = M_G_CPU1_SA_DQ<20>
  VSS14  = GND
  DQ21_A  = M_G_CPU1_SA_DQ<21>
  VSS15  = GND
  DQ24_A  = M_G_CPU1_SA_DQ<24>
  VSS16  = GND
  DQ25_A  = M_G_CPU1_SA_DQ<25>
  VSS17  = GND
  DQS3_A_T  = M_G_CPU1_SA_DQS_DP<3>
  DQS3_A_C  = M_G_CPU1_SA_DQS_DN<3>
  VSS18  = GND
  DQ28_A  = M_G_CPU1_SA_DQ<28>
  VSS19  = GND
  DQ29_A  = M_G_CPU1_SA_DQ<29>
  VSS20  = GND
  CB0_A  = M_G_CPU1_SA_CB<0>
  VSS21  = GND
  CB1_A  = M_G_CPU1_SA_CB<1>
  VSS22  = GND
  DQS4_A_T  = M_G_CPU1_SA_DQS_DP<4>
  DQS4_A_C  = M_G_CPU1_SA_DQS_DN<4>
  VSS23  = GND
  CB4_A  = M_G_CPU1_SA_CB<4>
  VSS24  = GND
  CB5_A  = M_G_CPU1_SA_CB<5>
  VSS25  = GND
  ALERT_N  = M_G_CPU1_ALERT_N
  VSS26  = GND
  CS0_A_N  = M_G_CPU1_SA_CS_N<2>
  VSS27  = GND
  CA0_A  = M_G_CPU1_SA_CA<0>
  VSS28  = GND
  CA2_A  = M_G_CPU1_SA_CA<2>
  VSS29  = GND
  CA4_A  = M_G_CPU1_SA_CA<4>
  VSS30  = GND
  CA6_A  = M_G_CPU1_SA_CA<6>
  VSS31  = GND
  PAR_A  = M_G_CPU1_SA_PAR
  VSS32  = GND
  CA0_B  = M_G_CPU1_SB_CA<0>
  VSS33  = GND
  CA2_B  = M_G_CPU1_SB_CA<2>
  VSS34  = GND
  CA4_B  = M_G_CPU1_SB_CA<4>
  VSS35  = GND
  CA6_B  = M_G_CPU1_SB_CA<6>
  VSS36  = GND
  CS0_B_N  = M_G_CPU1_SB_CS_N<2>
  VSS37  = GND
  \lbd||rsp_a_n\  = M_G_CPU1_SA_RSP<1>
  \lbs||rsp_b_n\  = M_G_CPU1_SB_RSP<1>
  VSS38  = GND
  CB4_B  = M_G_CPU1_SB_CB<4>
  VSS39  = GND
  CB5_B  = M_G_CPU1_SB_CB<5>
  VSS40  = GND
  \dqs9_b_t||tdqs9_b_t||dbi4_b_n\  = M_G_CPU1_SB_DQS_DP<9>
  \dqs9_b_c||tdqs9_b_c\  = M_G_CPU1_SB_DQS_DN<9>
  VSS41  = GND
  CB0_B  = M_G_CPU1_SB_CB<0>
  VSS42  = GND
  CB1_B  = M_G_CPU1_SB_CB<1>
  VSS43  = GND
  DQ0_B  = M_G_CPU1_SB_DQ<0>
  VSS44  = GND
  DQ1_B  = M_G_CPU1_SB_DQ<1>
  VSS45  = GND
  DQS0_B_T  = M_G_CPU1_SB_DQS_DP<0>
  DQS0_B_C  = M_G_CPU1_SB_DQS_DN<0>
  VSS46  = GND
  DQ4_B  = M_G_CPU1_SB_DQ<4>
  VSS47  = GND
  DQ5_B  = M_G_CPU1_SB_DQ<5>
  VSS48  = GND
  DQ8_B  = M_G_CPU1_SB_DQ<8>
  VSS49  = GND
  DQ9_B  = M_G_CPU1_SB_DQ<9>
  VSS50  = GND
  DQS1_B_T  = M_G_CPU1_SB_DQS_DP<1>
  DQS1_B_C  = M_G_CPU1_SB_DQS_DN<1>
  VSS51  = GND
  DQ12_B  = M_G_CPU1_SB_DQ<12>
  VSS52  = GND
  DQ13_B  = M_G_CPU1_SB_DQ<13>
  VSS53  = GND
  DQ16_B  = M_G_CPU1_SB_DQ<16>
  VSS54  = GND
  DQ17_B  = M_G_CPU1_SB_DQ<17>
  VSS55  = GND
  DQS2_B_T  = M_G_CPU1_SB_DQS_DP<2>
  DQS2_B_C  = M_G_CPU1_SB_DQS_DN<2>
  VSS56  = GND
  DQ20_B  = M_G_CPU1_SB_DQ<20>
  VSS57  = GND
  DQ21_B  = M_G_CPU1_SB_DQ<21>
  VSS58  = GND
  DQ24_B  = M_G_CPU1_SB_DQ<24>
  VSS59  = GND
  DQ25_B  = M_G_CPU1_SB_DQ<25>
  VSS60  = GND
  DQS3_B_T  = M_G_CPU1_SB_DQS_DP<3>
  DQS3_B_C  = M_G_CPU1_SB_DQS_DN<3>
  VSS61  = GND
  DQ28_B  = M_G_CPU1_SB_DQ<28>
  VSS62  = GND
  DQ29_B  = M_G_CPU1_SB_DQ<29>
  VSS63  = GND
  RFU1  = TP_CHG_CPU1_DIMM2_FRU_1
  VIN_BULK1  = P12V_S3_AUX_CPU1_NVDIMM
  VIN_BULK2  = P12V_S3_AUX_CPU1_NVDIMM
  \pwr_good||fail_n\  = PWRGD_CHG_CPU1_DIMM2
  HSA  = PD_CHG_CPU1_DIMM2_SAA
  RFU2  = TP_CHG_CPU1_DIMM2_FRU_2
  RFU3  = TP_CHG_CPU1_DIMM2_FRU_3
  VSS64  = GND
  DQ2_A  = M_G_CPU1_SA_DQ<2>
  VSS65  = GND
  DQ3_A  = M_G_CPU1_SA_DQ<3>
  VSS66  = GND
  \dqs5_a_c||tdqs5_a_c||dqs5_a_t||tdqs5_a_t\  = M_G_CPU1_SA_DQS_DN<5>
  \dqs5_a_t||tdqs5_a_t\  = M_G_CPU1_SA_DQS_DP<5>
  VSS67  = GND
  DQ6_A  = M_G_CPU1_SA_DQ<6>
  VSS68  = GND
  DQ7_A  = M_G_CPU1_SA_DQ<7>
  VSS69  = GND
  DQ10_A  = M_G_CPU1_SA_DQ<10>
  VSS70  = GND
  DQ11_A  = M_G_CPU1_SA_DQ<11>
  VSS71  = GND
  \dqs6_a_c||tdqs6_a_c||dqs6_a_t||tdqs6_a_t\  = M_G_CPU1_SA_DQS_DN<6>
  \dqs6_a_t||tdqs6_a_t\  = M_G_CPU1_SA_DQS_DP<6>
  VSS72  = GND
  DQ14_A  = M_G_CPU1_SA_DQ<14>
  VSS73  = GND
  DQ15_A  = M_G_CPU1_SA_DQ<15>
  VSS74  = GND
  DQ18_A  = M_G_CPU1_SA_DQ<18>
  VSS75  = GND
  DQ19_A  = M_G_CPU1_SA_DQ<19>
  VSS76  = GND
  \dqs7_a_c||tdqs7_a_c\  = M_G_CPU1_SA_DQS_DN<7>
  \dqs7_a_t||tdqs7_a_t\  = M_G_CPU1_SA_DQS_DP<7>
  VSS77  = GND
  DQ22_A  = M_G_CPU1_SA_DQ<22>
  VSS78  = GND
  DQ23_A  = M_G_CPU1_SA_DQ<23>
  VSS79  = GND
  DQ26_A  = M_G_CPU1_SA_DQ<26>
  VSS80  = GND
  DQ27_A  = M_G_CPU1_SA_DQ<27>
  VSS81  = GND
  \dqs8_a_c||tdqs8_a_c\  = M_G_CPU1_SA_DQS_DN<8>
  \dqs8_a_t||tdqs8_a_t\  = M_G_CPU1_SA_DQS_DP<8>
  VSS82  = GND
  DQ30_A  = M_G_CPU1_SA_DQ<30>
  VSS83  = GND
  DQ31_A  = M_G_CPU1_SA_DQ<31>
  VSS84  = GND
  CB2_A  = M_G_CPU1_SA_CB<2>
  VSS85  = GND
  CB3_A  = M_G_CPU1_SA_CB<3>
  VSS86  = GND
  \dqs9_a_c||tdqs9_a_c\  = M_G_CPU1_SA_DQS_DN<9>
  \dqs9_a_t||tdqs9_a_t\  = M_G_CPU1_SA_DQS_DP<9>
  VSS87  = GND
  CB6_A  = M_G_CPU1_SA_CB<6>
  VSS88  = GND
  CB7_A  = M_G_CPU1_SA_CB<7>
  VSS89  = GND
  RESET_N  = RST_M_GH_CPU1_FPGA_N
  VSS90  = GND
  CS1_A_N  = M_G_CPU1_SA_CS_N<3>
  VSS91  = GND
  CA1_A  = M_G_CPU1_SA_CA<1>
  VSS92  = GND
  CA3_A  = M_G_CPU1_SA_CA<3>
  VSS93  = GND
  CA5_A  = M_G_CPU1_SA_CA<5>
  VSS94  = GND
  CK_T  = M_G_CPU1_CLK_DP<1>
  CK_C  = M_G_CPU1_CLK_DN<1>
  VSS95  = GND
  RFU4  = TP_CHG_CPU1_DIMM2_FRU_4
  CA1_B  = M_G_CPU1_SB_CA<1>
  VSS96  = GND
  CA3_B  = M_G_CPU1_SB_CA<3>
  VSS97  = GND
  CA5_B  = M_G_CPU1_SB_CA<5>
  VSS98  = GND
  PAR_B  = M_G_CPU1_SB_PAR
  VSS99  = GND
  CS1_B_N  = M_G_CPU1_SB_CS_N<3>
  VSS100  = GND
  RFU5  = TP_CHG_CPU1_DIMM2_FRU_5
  RFU6  = TP_CHG_CPU1_DIMM2_FRU_6
  VSS101  = GND
  CB6_B  = M_G_CPU1_SB_CB<6>
  VSS102  = GND
  CB7_B  = M_G_CPU1_SB_CB<7>
  VSS103  = GND
  DQS4_B_C  = M_G_CPU1_SB_DQS_DN<4>
  DQS4_B_T  = M_G_CPU1_SB_DQS_DP<4>
  VSS104  = GND
  CB2_B  = M_G_CPU1_SB_CB<2>
  VSS105  = GND
  CB3_B  = M_G_CPU1_SB_CB<3>
  VSS106  = GND
  DQ2_B  = M_G_CPU1_SB_DQ<2>
  VSS107  = GND
  DQ3_B  = M_G_CPU1_SB_DQ<3>
  VSS108  = GND
  \dqs5_b_c||tdqs5_b_c\  = M_G_CPU1_SB_DQS_DN<5>
  \dqs5_b_t||tdqs5_b_t\  = M_G_CPU1_SB_DQS_DP<5>
  VSS109  = GND
  DQ6_B  = M_G_CPU1_SB_DQ<6>
  VSS110  = GND
  DQ7_B  = M_G_CPU1_SB_DQ<7>
  VSS111  = GND
  DQ10_B  = M_G_CPU1_SB_DQ<10>
  VSS112  = GND
  DQ11_B  = M_G_CPU1_SB_DQ<11>
  VSS113  = GND
  \dqs6_b_c||tdqs6_b_c\  = M_G_CPU1_SB_DQS_DN<6>
  \dqs6_b_t||tdqs6_b_t\  = M_G_CPU1_SB_DQS_DP<6>
  VSS114  = GND
  DQ14_B  = M_G_CPU1_SB_DQ<14>
  VSS115  = GND
  DQ15_B  = M_G_CPU1_SB_DQ<15>
  VSS116  = GND
  DQ18_B  = M_G_CPU1_SB_DQ<18>
  VSS117  = GND
  DQ19_B  = M_G_CPU1_SB_DQ<19>
  VSS118  = GND
  \dqs7_b_c||tdqs7_b_c\  = M_G_CPU1_SB_DQS_DN<7>
  \dqs7_b_t||tdqs7_b_t\  = M_G_CPU1_SB_DQS_DP<7>
  VSS119  = GND
  DQ22_B  = M_G_CPU1_SB_DQ<22>
  VSS120  = GND
  DQ23_B  = M_G_CPU1_SB_DQ<23>
  VSS121  = GND
  DQ26_B  = M_G_CPU1_SB_DQ<26>
  VSS122  = GND
  DQ27_B  = M_G_CPU1_SB_DQ<27>
  VSS123  = GND
  \dqs8_b_c||tdqs8_b_c\  = M_G_CPU1_SB_DQS_DN<8>
  \dqs8_b_t||tdqs8_b_t\  = M_G_CPU1_SB_DQS_DP<8>
  VSS124  = GND
  DQ30_B  = M_G_CPU1_SB_DQ<30>
  VSS125  = GND
  DQ31_B  = M_G_CPU1_SB_DQ<31>
  VSS126  = GND
  G1  = GND
  G2  = GND
  G3  = GND

(kicad_pcb
	(version 20260206)
	(generator "pcbnew")
	(generator_version "10.0")
	(general
		(thickness 1.6)
		(legacy_teardrops no)
	)
	(paper "A4")
	(title_block
		(title "03242023_DA0F0TMBIJ0_F0T_Motherboard_J_brd_V01_OCP.brd")
		(comment 1 "Grand Teton / footprint 1354 of 6105 (J30), pads 1-45 of 291")
	)
	(layers
		(0 "F.Cu" signal "TOP")
		(4 "In1.Cu" signal "GND")
		(6 "In2.Cu" signal "IN1")
		(8 "In3.Cu" signal "GND1")
		(10 "In4.Cu" signal "IN2")
		(12 "In5.Cu" signal "GND2")
		(14 "In6.Cu" signal "IN3")
		(16 "In7.Cu" signal "GND3")
		(18 "In8.Cu" signal "VCC")
		(20 "In9.Cu" signal "VCC1")
		(22 "In10.Cu" signal "GND4")
		(24 "In11.Cu" signal "IN4")
		(26 "In12.Cu" signal "GND5")
		(28 "In13.Cu" signal "IN5")
		(30 "In14.Cu" signal "GND6")
		(32 "In15.Cu" signal "IN6")
		(34 "In16.Cu" signal "GND7")
		(2 "B.Cu" signal "BOTTOM")
		(9 "F.Adhes" user "F.Adhesive")
		(11 "B.Adhes" user "B.Adhesive")
		(13 "F.Paste" user "Package Geometry/Pastemask Top")
		(15 "B.Paste" user "Package Geometry/Pastemask Bottom")
		(5 "F.SilkS" user "Ref Des/Silkscreen Top")
		(7 "B.SilkS" user "Ref Des/Silkscreen Bottom")
		(1 "F.Mask" user "Board Geometry/Soldermask Top")
		(3 "B.Mask" user "Board Geometry/Soldermask Bottom")
		(17 "Dwgs.User" user "User.Drawings")
		(19 "Cmts.User" user "User.Comments")
		(21 "Eco1.User" user "User.Eco1")
		(23 "Eco2.User" user "User.Eco2")
		(25 "Edge.Cuts" user "Board Geometry/Outline")
		(27 "Margin" user)
		(31 "F.CrtYd" user "Package Geometry/Place Bound Top")
		(29 "B.CrtYd" user "Package Geometry/Place Bound Bottom")
		(35 "F.Fab" user "Ref Des/Assembly Top")
		(33 "B.Fab" user "Ref Des/Assembly Bottom")
	)
	(footprint ""
		(layer "F.Cu")
		(at 191.03848 -258.091686)
		(property "Reference" "J30"
			(at -2.98196 -81.740248 0)
			(unlocked yes)
			(layer "F.SilkS")
			(effects
				(font
					(size 0.7874 0.5842)
					(thickness 0.1524)
				)
				(justify left)
			)
		)
		(property "Value" ""
			(at 0 0 0)
			(layer "F.Fab")
			(effects
				(font
					(size 1.27 1.27)
				)
			)
		)
		(duplicate_pad_numbers_are_jumpers no)
		(pad "1" smd rect
			(at -2.050034 -63.324994 270)
			(size 0.519938 1.4986)
			(layers "F.Cu" "F.Mask" "F.Paste")
			(net "P12V_S3_AUX_CPU1_NVDIMM")
		)
		(pad "2" smd rect
			(at -2.050034 -62.47511 270)
			(size 0.519938 1.4986)
			(layers "F.Cu" "F.Mask" "F.Paste")
			(net "TP_CHG_CPU1_DIMM2_FRU_0")
		)
		(pad "3" smd rect
			(at -2.050034 -61.624972 270)
			(size 0.519938 1.4986)
			(layers "F.Cu" "F.Mask" "F.Paste")
			(net "P3V3_AUX")
		)
		(pad "4" smd rect
			(at -2.050034 -60.775088 270)
			(size 0.519938 1.4986)
			(layers "F.Cu" "F.Mask" "F.Paste")
			(net "I3C_SPD_DDREFGH_CPU1_LVC1_SCL_5")
		)
		(pad "5" smd rect
			(at -2.050034 -59.92495 270)
			(size 0.519938 1.4986)
			(layers "F.Cu" "F.Mask" "F.Paste")
			(net "I3C_SPD_DDREFGH_CPU1_LVC1_SDA")
		)
		(pad "6" smd rect
			(at -2.050034 -59.075066 270)
			(size 0.519938 1.4986)
			(layers "F.Cu" "F.Mask" "F.Paste")
			(net "GND")
		)
		(pad "7" smd rect
			(at -2.050034 -58.224928 270)
			(size 0.519938 1.4986)
			(layers "F.Cu" "F.Mask" "F.Paste")
			(net "M_G_CPU1_SA_DQ<0>")
		)
		(pad "8" smd rect
			(at -2.050034 -57.375044 270)
			(size 0.519938 1.4986)
			(layers "F.Cu" "F.Mask" "F.Paste")
			(net "GND")
		)
		(pad "9" smd rect
			(at -2.050034 -56.524906 270)
			(size 0.519938 1.4986)
			(layers "F.Cu" "F.Mask" "F.Paste")
			(net "M_G_CPU1_SA_DQ<1>")
		)
		(pad "10" smd rect
			(at -2.050034 -55.675022 270)
			(size 0.519938 1.4986)
			(layers "F.Cu" "F.Mask" "F.Paste")
			(net "GND")
		)
		(pad "11" smd rect
			(at -2.050034 -54.824884 270)
			(size 0.519938 1.4986)
			(layers "F.Cu" "F.Mask" "F.Paste")
			(net "M_G_CPU1_SA_DQS_DP<0>")
		)
		(pad "12" smd rect
			(at -2.050034 -53.975 270)
			(size 0.519938 1.4986)
			(layers "F.Cu" "F.Mask" "F.Paste")
			(net "M_G_CPU1_SA_DQS_DN<0>")
		)
		(pad "13" smd rect
			(at -2.050034 -53.125116 270)
			(size 0.519938 1.4986)
			(layers "F.Cu" "F.Mask" "F.Paste")
			(net "GND")
		)
		(pad "14" smd rect
			(at -2.050034 -52.274978 270)
			(size 0.519938 1.4986)
			(layers "F.Cu" "F.Mask" "F.Paste")
			(net "M_G_CPU1_SA_DQ<4>")
		)
		(pad "15" smd rect
			(at -2.050034 -51.425094 270)
			(size 0.519938 1.4986)
			(layers "F.Cu" "F.Mask" "F.Paste")
			(net "GND")
		)
		(pad "16" smd rect
			(at -2.050034 -50.574956 270)
			(size 0.519938 1.4986)
			(layers "F.Cu" "F.Mask" "F.Paste")
			(net "M_G_CPU1_SA_DQ<5>")
		)
		(pad "17" smd rect
			(at -2.050034 -49.725072 270)
			(size 0.519938 1.4986)
			(layers "F.Cu" "F.Mask" "F.Paste")
			(net "GND")
		)
		(pad "18" smd rect
			(at -2.050034 -48.874934 270)
			(size 0.519938 1.4986)
			(layers "F.Cu" "F.Mask" "F.Paste")
			(net "M_G_CPU1_SA_DQ<8>")
		)
		(pad "19" smd rect
			(at -2.050034 -48.02505 270)
			(size 0.519938 1.4986)
			(layers "F.Cu" "F.Mask" "F.Paste")
			(net "GND")
		)
		(pad "20" smd rect
			(at -2.050034 -47.174912 270)
			(size 0.519938 1.4986)
			(layers "F.Cu" "F.Mask" "F.Paste")
			(net "M_G_CPU1_SA_DQ<9>")
		)
		(pad "21" smd rect
			(at -2.050034 -46.325028 270)
			(size 0.519938 1.4986)
			(layers "F.Cu" "F.Mask" "F.Paste")
			(net "GND")
		)
		(pad "22" smd rect
			(at -2.050034 -45.47489 270)
			(size 0.519938 1.4986)
			(layers "F.Cu" "F.Mask" "F.Paste")
			(net "M_G_CPU1_SA_DQS_DP<1>")
		)
		(pad "23" smd rect
			(at -2.050034 -44.625006 270)
			(size 0.519938 1.4986)
			(layers "F.Cu" "F.Mask" "F.Paste")
			(net "M_G_CPU1_SA_DQS_DN<1>")
		)
		(pad "24" smd rect
			(at -2.050034 -43.775122 270)
			(size 0.519938 1.4986)
			(layers "F.Cu" "F.Mask" "F.Paste")
			(net "GND")
		)
		(pad "25" smd rect
			(at -2.050034 -42.924984 270)
			(size 0.519938 1.4986)
			(layers "F.Cu" "F.Mask" "F.Paste")
			(net "M_G_CPU1_SA_DQ<12>")
		)
		(pad "26" smd rect
			(at -2.050034 -42.0751 270)
			(size 0.519938 1.4986)
			(layers "F.Cu" "F.Mask" "F.Paste")
			(net "GND")
		)
		(pad "27" smd rect
			(at -2.050034 -41.224962 270)
			(size 0.519938 1.4986)
			(layers "F.Cu" "F.Mask" "F.Paste")
			(net "M_G_CPU1_SA_DQ<13>")
		)
		(pad "28" smd rect
			(at -2.050034 -40.375078 270)
			(size 0.519938 1.4986)
			(layers "F.Cu" "F.Mask" "F.Paste")
			(net "GND")
		)
		(pad "29" smd rect
			(at -2.050034 -39.52494 270)
			(size 0.519938 1.4986)
			(layers "F.Cu" "F.Mask" "F.Paste")
			(net "M_G_CPU1_SA_DQ<16>")
		)
		(pad "30" smd rect
			(at -2.050034 -38.675056 270)
			(size 0.519938 1.4986)
			(layers "F.Cu" "F.Mask" "F.Paste")
			(net "GND")
		)
		(pad "31" smd rect
			(at -2.050034 -37.824918 270)
			(size 0.519938 1.4986)
			(layers "F.Cu" "F.Mask" "F.Paste")
			(net "M_G_CPU1_SA_DQ<17>")
		)
		(pad "32" smd rect
			(at -2.050034 -36.975034 270)
			(size 0.519938 1.4986)
			(layers "F.Cu" "F.Mask" "F.Paste")
			(net "GND")
		)
		(pad "33" smd rect
			(at -2.050034 -36.124896 270)
			(size 0.519938 1.4986)
			(layers "F.Cu" "F.Mask" "F.Paste")
			(net "M_G_CPU1_SA_DQS_DP<2>")
		)
		(pad "34" smd rect
			(at -2.050034 -35.275012 270)
			(size 0.519938 1.4986)
			(layers "F.Cu" "F.Mask" "F.Paste")
			(net "M_G_CPU1_SA_DQS_DN<2>")
		)
		(pad "35" smd rect
			(at -2.050034 -34.425128 270)
			(size 0.519938 1.4986)
			(layers "F.Cu" "F.Mask" "F.Paste")
			(net "GND")
		)
		(pad "36" smd rect
			(at -2.050034 -33.57499 270)
			(size 0.519938 1.4986)
			(layers "F.Cu" "F.Mask" "F.Paste")
			(net "M_G_CPU1_SA_DQ<20>")
		)
		(pad "37" smd rect
			(at -2.050034 -32.725106 270)
			(size 0.519938 1.4986)
			(layers "F.Cu" "F.Mask" "F.Paste")
			(net "GND")
		)
		(pad "38" smd rect
			(at -2.050034 -31.874968 270)
			(size 0.519938 1.4986)
			(layers "F.Cu" "F.Mask" "F.Paste")
			(net "M_G_CPU1_SA_DQ<21>")
		)
		(pad "39" smd rect
			(at -2.050034 -31.025084 270)
			(size 0.519938 1.4986)
			(layers "F.Cu" "F.Mask" "F.Paste")
			(net "GND")
		)
		(pad "40" smd rect
			(at -2.050034 -30.174946 270)
			(size 0.519938 1.4986)
			(layers "F.Cu" "F.Mask" "F.Paste")
			(net "M_G_CPU1_SA_DQ<24>")
		)
		(pad "41" smd rect
			(at -2.050034 -29.325062 270)
			(size 0.519938 1.4986)
			(layers "F.Cu" "F.Mask" "F.Paste")
			(net "GND")
		)
		(pad "42" smd rect
			(at -2.050034 -28.474924 270)
			(size 0.519938 1.4986)
			(layers "F.Cu" "F.Mask" "F.Paste")
			(net "M_G_CPU1_SA_DQ<25>")
		)
		(pad "43" smd rect
			(at -2.050034 -27.62504 270)
			(size 0.519938 1.4986)
			(layers "F.Cu" "F.Mask" "F.Paste")
			(net "GND")
		)
		(pad "44" smd rect
			(at -2.050034 -26.774902 270)
			(size 0.519938 1.4986)
			(layers "F.Cu" "F.Mask" "F.Paste")
			(net "M_G_CPU1_SA_DQS_DP<3>")
		)
		(pad "45" smd rect
			(at -2.050034 -25.925018 270)
			(size 0.519938 1.4986)
			(layers "F.Cu" "F.Mask" "F.Paste")
			(net "M_G_CPU1_SA_DQS_DN<3>")
		)
	)
)
